# T6G (Grand Teton) — schematic netlist excerpt (pin names and nets, part order shuffled) for the footprints in the layout excerpt that follows; sources: Cadence DE-HDL packaged netlist, KiCad conversion of 04192023_DAF0TMB3IC0_F0TG_MB_C_brd_V02_OCP.brd

R3772  Q_RES  0 5% CHIP  pkg 0402LF  page 145 : A = RST_SMB_BUF_E1S_0_N ; B = RST_SMB_E1S_0_N

(kicad_pcb
	(version 20260206)
	(generator "pcbnew")
	(generator_version "10.0")
	(general
		(thickness 1.6)
		(legacy_teardrops no)
	)
	(paper "A4")
	(title_block
		(title "04192023_DAF0TMB3IC0_F0TG_MB_C_brd_V02_OCP.brd")
		(comment 1 "Grand Teton / footprints 4247-4247 of 8354")
	)
	(layers
		(0 "F.Cu" signal "TOP")
		(4 "In1.Cu" signal "GND")
		(6 "In2.Cu" signal "IN1")
		(8 "In3.Cu" signal "GND1")
		(10 "In4.Cu" signal "IN2")
		(12 "In5.Cu" signal "GND2")
		(14 "In6.Cu" signal "IN3")
		(16 "In7.Cu" signal "GND3")
		(18 "In8.Cu" signal "VCC")
		(20 "In9.Cu" signal "VCC1")
		(22 "In10.Cu" signal "GND4")
		(24 "In11.Cu" signal "IN4")
		(26 "In12.Cu" signal "GND5")
		(28 "In13.Cu" signal "IN5")
		(30 "In14.Cu" signal "GND6")
		(32 "In15.Cu" signal "IN6")
		(34 "In16.Cu" signal "GND7")
		(2 "B.Cu" signal "BOTTOM")
		(9 "F.Adhes" user "F.Adhesive")
		(11 "B.Adhes" user "B.Adhesive")
		(13 "F.Paste" user "Package Geometry/Pastemask Top")
		(15 "B.Paste" user "Package Geometry/Pastemask Bottom")
		(5 "F.SilkS" user "Ref Des/Silkscreen Top")
		(7 "B.SilkS" user "Ref Des/Silkscreen Bottom")
		(1 "F.Mask" user "Board Geometry/Soldermask Top")
		(3 "B.Mask" user "Board Geometry/Soldermask Bottom")
		(17 "Dwgs.User" user "User.Drawings")
		(19 "Cmts.User" user "User.Comments")
		(21 "Eco1.User" user "User.Eco1")
		(23 "Eco2.User" user "User.Eco2")
		(25 "Edge.Cuts" user "Board Geometry/Outline")
		(27 "Margin" user)
		(31 "F.CrtYd" user "Package Geometry/Place Bound Top")
		(29 "B.CrtYd" user "Package Geometry/Place Bound Bottom")
		(35 "F.Fab" user "Ref Des/Assembly Top")
		(33 "B.Fab" user "Ref Des/Assembly Bottom")
	)
	(footprint ""
		(layer "F.Cu")
		(at 258.275836 -75.770994)
		(property "Reference" "R3772"
			(at 0 0 0)
			(layer "F.SilkS")
			(hide yes)
			(effects
				(font
					(size 1.27 1.27)
				)
			)
		)
		(property "Value" ""
			(at 0 0 0)
			(layer "F.Fab")
			(effects
				(font
					(size 1.27 1.27)
				)
			)
		)
		(duplicate_pad_numbers_are_jumpers no)
		(fp_line
			(start -0.7874 -0.4064)
			(end 0.7874 -0.4064)
			(stroke
				(width 0.1524)
				(type default)
			)
			(layer "F.SilkS")
		)
		(fp_line
			(start -0.7874 0.4064)
			(end -0.7874 -0.4064)
			(stroke
				(width 0.1524)
				(type default)
			)
			(layer "F.SilkS")
		)
		(fp_line
			(start 0.7874 -0.4064)
			(end 0.7874 0.4064)
			(stroke
				(width 0.1524)
				(type default)
			)
			(layer "F.SilkS")
		)
		(fp_line
			(start 0.7874 0.4064)
			(end -0.7874 0.4064)
			(stroke
				(width 0.1524)
				(type default)
			)
			(layer "F.SilkS")
		)
		(fp_line
			(start -0.67945 -0.305054)
			(end -0.12065 -0.305054)
			(stroke
				(width 0.1)
				(type default)
			)
			(layer "F.Fab")
		)
		(fp_line
			(start -0.67945 0.3048)
			(end -0.67945 -0.305054)
			(stroke
				(width 0.1)
				(type default)
			)
			(layer "F.Fab")
		)
		(fp_line
			(start -0.12065 -0.305054)
			(end -0.12065 -0.2794)
			(stroke
				(width 0.1)
				(type default)
			)
			(layer "F.Fab")
		)
		(fp_line
			(start -0.12065 -0.2794)
			(end 0.12065 -0.2794)
			(stroke
				(width 0.1)
				(type default)
			)
			(layer "F.Fab")
		)
		(fp_line
			(start -0.12065 0.2794)
			(end -0.12065 0.3048)
			(stroke
				(width 0.1)
				(type default)
			)
			(layer "F.Fab")
		)
		(fp_line
			(start -0.12065 0.3048)
			(end -0.67945 0.3048)
			(stroke
				(width 0.1)
				(type default)
			)
			(layer "F.Fab")
		)
		(fp_line
			(start 0.120396 0.2794)
			(end -0.12065 0.2794)
			(stroke
				(width 0.1)
				(type default)
			)
			(layer "F.Fab")
		)
		(fp_line
			(start 0.120396 0.3048)
			(end 0.120396 0.2794)
			(stroke
				(width 0.1)
				(type default)
			)
			(layer "F.Fab")
		)
		(fp_line
			(start 0.12065 -0.3048)
			(end 0.67945 -0.3048)
			(stroke
				(width 0.1)
				(type default)
			)
			(layer "F.Fab")
		)
		(fp_line
			(start 0.12065 -0.2794)
			(end 0.12065 -0.3048)
			(stroke
				(width 0.1)
				(type default)
			)
			(layer "F.Fab")
		)
		(fp_line
			(start 0.67945 -0.3048)
			(end 0.67945 0.3048)
			(stroke
				(width 0.1)
				(type default)
			)
			(layer "F.Fab")
		)
		(fp_line
			(start 0.67945 0.3048)
			(end 0.120396 0.3048)
			(stroke
				(width 0.1)
				(type default)
			)
			(layer "F.Fab")
		)
		(pad "1" smd circle
			(at -0.40005 0)
			(size 0 0)
			(layers "F.Cu" "F.Mask" "F.Paste")
			(net "RST_SMB_BUF_E1S_0_N")
		)
		(pad "2" smd circle
			(at 0.40005 0)
			(size 0 0)
			(layers "F.Cu" "F.Mask" "F.Paste")
			(net "RST_SMB_E1S_0_N")
		)
	)
)
